(kicad_pcb
	(version 20260206)
	(generator "pcbnew")
	(generator_version "10.0")
	(general
		(thickness 1.6)
		(legacy_teardrops no)
	)
	(paper "A4")
	(title_block
		(title "04192023_DAF0TMB3IC0_F0TG_MB_C_brd_V02_OCP.brd")
		(comment 1 "Grand Teton / footprints 477-483 of 8354")
	)
	(layers
		(0 "F.Cu" signal "TOP")
		(4 "In1.Cu" signal "GND")
		(6 "In2.Cu" signal "IN1")
		(8 "In3.Cu" signal "GND1")
		(10 "In4.Cu" signal "IN2")
		(12 "In5.Cu" signal "GND2")
		(14 "In6.Cu" signal "IN3")
		(16 "In7.Cu" signal "GND3")
		(18 "In8.Cu" signal "VCC")
		(20 "In9.Cu" signal "VCC1")
		(22 "In10.Cu" signal "GND4")
		(24 "In11.Cu" signal "IN4")
		(26 "In12.Cu" signal "GND5")
		(28 "In13.Cu" signal "IN5")
		(30 "In14.Cu" signal "GND6")
		(32 "In15.Cu" signal "IN6")
		(34 "In16.Cu" signal "GND7")
		(2 "B.Cu" signal "BOTTOM")
		(9 "F.Adhes" user "F.Adhesive")
		(11 "B.Adhes" user "B.Adhesive")
		(13 "F.Paste" user "Package Geometry/Pastemask Top")
		(15 "B.Paste" user "Package Geometry/Pastemask Bottom")
		(5 "F.SilkS" user "Ref Des/Silkscreen Top")
		(7 "B.SilkS" user "Ref Des/Silkscreen Bottom")
		(1 "F.Mask" user "Board Geometry/Soldermask Top")
		(3 "B.Mask" user "Board Geometry/Soldermask Bottom")
		(17 "Dwgs.User" user "User.Drawings")
		(19 "Cmts.User" user "User.Comments")
		(21 "Eco1.User" user "User.Eco1")
		(23 "Eco2.User" user "User.Eco2")
		(25 "Edge.Cuts" user "Board Geometry/Outline")
		(27 "Margin" user)
		(31 "F.CrtYd" user "Package Geometry/Place Bound Top")
		(29 "B.CrtYd" user "Package Geometry/Place Bound Bottom")
		(35 "F.Fab" user "Ref Des/Assembly Top")
		(33 "B.Fab" user "Ref Des/Assembly Bottom")
	)
	(footprint ""
		(layer "F.Cu")
		(at 117.895624 -259.355336 180)
		(property "Reference" "C2269"
			(at 0 0 180)
			(layer "F.SilkS")
			(hide yes)
			(effects
				(font
					(size 1.27 1.27)
				)
			)
		)
		(property "Value" ""
			(at 0 0 180)
			(layer "F.Fab")
			(effects
				(font
					(size 1.27 1.27)
				)
			)
		)
		(duplicate_pad_numbers_are_jumpers no)
		(fp_line
			(start 0.7874 0.4064)
			(end -0.7874 0.4064)
			(stroke
				(width 0.1524)
				(type default)
			)
			(layer "F.SilkS")
		)
		(fp_line
			(start 0.7874 -0.4064)
			(end 0.7874 0.4064)
			(stroke
				(width 0.1524)
				(type default)
			)
			(layer "F.SilkS")
		)
		(fp_line
			(start -0.7874 0.4064)
			(end -0.7874 -0.4064)
			(stroke
				(width 0.1524)
				(type default)
			)
			(layer "F.SilkS")
		)
		(fp_line
			(start -0.7874 -0.4064)
			(end 0.7874 -0.4064)
			(stroke
				(width 0.1524)
				(type default)
			)
			(layer "F.SilkS")
		)
		(fp_line
			(start 0.67945 0.3048)
			(end 0.120396 0.3048)
			(stroke
				(width 0.1)
				(type default)
			)
			(layer "F.Fab")
		)
		(fp_line
			(start 0.67945 -0.3048)
			(end 0.67945 0.3048)
			(stroke
				(width 0.1)
				(type default)
			)
			(layer "F.Fab")
		)
		(fp_line
			(start 0.12065 -0.2794)
			(end 0.12065 -0.3048)
			(stroke
				(width 0.1)
				(type default)
			)
			(layer "F.Fab")
		)
		(fp_line
			(start 0.12065 -0.3048)
			(end 0.67945 -0.3048)
			(stroke
				(width 0.1)
				(type default)
			)
			(layer "F.Fab")
		)
		(fp_line
			(start 0.120396 0.3048)
			(end 0.120396 0.2794)
			(stroke
				(width 0.1)
				(type default)
			)
			(layer "F.Fab")
		)
		(fp_line
			(start 0.120396 0.2794)
			(end -0.12065 0.2794)
			(stroke
				(width 0.1)
				(type default)
			)
			(layer "F.Fab")
		)
		(fp_line
			(start -0.12065 0.3048)
			(end -0.67945 0.3048)
			(stroke
				(width 0.1)
				(type default)
			)
			(layer "F.Fab")
		)
		(fp_line
			(start -0.12065 0.2794)
			(end -0.12065 0.3048)
			(stroke
				(width 0.1)
				(type default)
			)
			(layer "F.Fab")
		)
		(fp_line
			(start -0.12065 -0.2794)
			(end 0.12065 -0.2794)
			(stroke
				(width 0.1)
				(type default)
			)
			(layer "F.Fab")
		)
		(fp_line
			(start -0.12065 -0.305054)
			(end -0.12065 -0.2794)
			(stroke
				(width 0.1)
				(type default)
			)
			(layer "F.Fab")
		)
		(fp_line
			(start -0.67945 0.3048)
			(end -0.67945 -0.305054)
			(stroke
				(width 0.1)
				(type default)
			)
			(layer "F.Fab")
		)
		(fp_line
			(start -0.67945 -0.305054)
			(end -0.12065 -0.305054)
			(stroke
				(width 0.1)
				(type default)
			)
			(layer "F.Fab")
		)
		(pad "1" smd circle
			(at -0.40005 0 180)
			(size 0 0)
			(layers "F.Cu" "F.Mask" "F.Paste")
			(net "PVDDCR_SOC_P1")
		)
		(pad "2" smd circle
			(at 0.40005 0 180)
			(size 0 0)
			(layers "F.Cu" "F.Mask" "F.Paste")
			(net "GND")
		)
	)
	(footprint ""
		(layer "F.Cu")
		(at 328.694542 -393.9032 90)
		(property "Reference" "R966"
			(at 0 0 90)
			(layer "F.SilkS")
			(hide yes)
			(effects
				(font
					(size 1.27 1.27)
				)
			)
		)
		(property "Value" ""
			(at 0 0 90)
			(layer "F.Fab")
			(effects
				(font
					(size 1.27 1.27)
				)
			)
		)
		(duplicate_pad_numbers_are_jumpers no)
		(fp_line
			(start 0.32512 -0.175006)
			(end 0.32512 0.175006)
			(stroke
				(width 0.1)
				(type default)
			)
			(layer "F.Fab")
		)
		(fp_line
			(start -0.32512 -0.175006)
			(end 0.32512 -0.175006)
			(stroke
				(width 0.1)
				(type default)
			)
			(layer "F.Fab")
		)
		(fp_line
			(start 0.32512 0.175006)
			(end -0.32512 0.175006)
			(stroke
				(width 0.1)
				(type default)
			)
			(layer "F.Fab")
		)
		(fp_line
			(start -0.32512 0.175006)
			(end -0.32512 -0.175006)
			(stroke
				(width 0.1)
				(type default)
			)
			(layer "F.Fab")
		)
		(pad "1" smd rect
			(at -0.2667 0 90)
			(size 0.3048 0.381)
			(layers "F.Cu" "F.Mask" "F.Paste")
			(net "P1V8_CPU0_RT_1D")
		)
		(pad "2" smd rect
			(at 0.2667 0 270)
			(size 0.3048 0.381)
			(layers "F.Cu" "F.Mask" "F.Paste")
			(net "RT_CPU0_P0_ADDR2")
		)
	)
	(footprint ""
		(layer "F.Cu")
		(at 186.817 -100.294948 90)
		(property "Reference" "R6053"
			(at 0 0 90)
			(layer "F.SilkS")
			(hide yes)
			(effects
				(font
					(size 1.27 1.27)
				)
			)
		)
		(property "Value" ""
			(at 0 0 90)
			(layer "F.Fab")
			(effects
				(font
					(size 1.27 1.27)
				)
			)
		)
		(duplicate_pad_numbers_are_jumpers no)
		(fp_line
			(start 0.7874 -0.4064)
			(end 0.7874 0.4064)
			(stroke
				(width 0.1524)
				(type default)
			)
			(layer "F.SilkS")
		)
		(fp_line
			(start -0.7874 -0.4064)
			(end 0.7874 -0.4064)
			(stroke
				(width 0.1524)
				(type default)
			)
			(layer "F.SilkS")
		)
		(fp_line
			(start 0.7874 0.4064)
			(end -0.7874 0.4064)
			(stroke
				(width 0.1524)
				(type default)
			)
			(layer "F.SilkS")
		)
		(fp_line
			(start -0.7874 0.4064)
			(end -0.7874 -0.4064)
			(stroke
				(width 0.1524)
				(type default)
			)
			(layer "F.SilkS")
		)
		(fp_line
			(start -0.12065 -0.305054)
			(end -0.12065 -0.2794)
			(stroke
				(width 0.1)
				(type default)
			)
			(layer "F.Fab")
		)
		(fp_line
			(start -0.67945 -0.305054)
			(end -0.12065 -0.305054)
			(stroke
				(width 0.1)
				(type default)
			)
			(layer "F.Fab")
		)
		(fp_line
			(start 0.67945 -0.3048)
			(end 0.67945 0.3048)
			(stroke
				(width 0.1)
				(type default)
			)
			(layer "F.Fab")
		)
		(fp_line
			(start 0.12065 -0.3048)
			(end 0.67945 -0.3048)
			(stroke
				(width 0.1)
				(type default)
			)
			(layer "F.Fab")
		)
		(fp_line
			(start 0.12065 -0.2794)
			(end 0.12065 -0.3048)
			(stroke
				(width 0.1)
				(type default)
			)
			(layer "F.Fab")
		)
		(fp_line
			(start -0.12065 -0.2794)
			(end 0.12065 -0.2794)
			(stroke
				(width 0.1)
				(type default)
			)
			(layer "F.Fab")
		)
		(fp_line
			(start 0.120396 0.2794)
			(end -0.12065 0.2794)
			(stroke
				(width 0.1)
				(type default)
			)
			(layer "F.Fab")
		)
		(fp_line
			(start -0.12065 0.2794)
			(end -0.12065 0.3048)
			(stroke
				(width 0.1)
				(type default)
			)
			(layer "F.Fab")
		)
		(fp_line
			(start 0.67945 0.3048)
			(end 0.120396 0.3048)
			(stroke
				(width 0.1)
				(type default)
			)
			(layer "F.Fab")
		)
		(fp_line
			(start 0.120396 0.3048)
			(end 0.120396 0.2794)
			(stroke
				(width 0.1)
				(type default)
			)
			(layer "F.Fab")
		)
		(fp_line
			(start -0.12065 0.3048)
			(end -0.67945 0.3048)
			(stroke
				(width 0.1)
				(type default)
			)
			(layer "F.Fab")
		)
		(fp_line
			(start -0.67945 0.3048)
			(end -0.67945 -0.305054)
			(stroke
				(width 0.1)
				(type default)
			)
			(layer "F.Fab")
		)
		(pad "1" smd circle
			(at -0.40005 0 90)
			(size 0 0)
			(layers "F.Cu" "F.Mask" "F.Paste")
			(net "M2_SSD0_CLKREQ_EN_N")
		)
		(pad "2" smd circle
			(at 0.40005 0 90)
			(size 0 0)
			(layers "F.Cu" "F.Mask" "F.Paste")
			(net "FM_CLKREQ_M2_1_N")
		)
	)
	(footprint ""
		(layer "F.Cu")
		(at 389.291322 -192.061084 180)
		(property "Reference" "PL60"
			(at -5.632196 3.113278 90)
			(unlocked yes)
			(layer "F.SilkS")
			(effects
				(font
					(size 0.7874 0.5842)
					(thickness 0.1524)
				)
				(justify left)
			)
		)
		(property "Value" ""
			(at 0 0 180)
			(layer "F.Fab")
			(effects
				(font
					(size 1.27 1.27)
				)
			)
		)
		(duplicate_pad_numbers_are_jumpers no)
		(fp_line
			(start 3.750056 5.500116)
			(end 3.750056 -5.500116)
			(stroke
				(width 0.1524)
				(type default)
			)
			(layer "F.SilkS")
		)
		(fp_line
			(start 3.750056 -5.500116)
			(end 2.393442 -5.500116)
			(stroke
				(width 0.1524)
				(type default)
			)
			(layer "F.SilkS")
		)
		(fp_line
			(start 2.393442 5.500116)
			(end 3.750056 5.500116)
			(stroke
				(width 0.1524)
				(type default)
			)
			(layer "F.SilkS")
		)
		(fp_line
			(start -2.393442 5.500116)
			(end -3.750056 5.500116)
			(stroke
				(width 0.1524)
				(type default)
			)
			(layer "F.SilkS")
		)
		(fp_line
			(start -3.750056 5.500116)
			(end -3.750056 -5.500116)
			(stroke
				(width 0.1524)
				(type default)
			)
			(layer "F.SilkS")
		)
		(fp_line
			(start -3.750056 -5.500116)
			(end -2.393442 -5.500116)
			(stroke
				(width 0.1524)
				(type default)
			)
			(layer "F.SilkS")
		)
		(fp_poly
			(pts
				(xy -3.9116 -4.249928) (xy -4.662678 -3.874516) (xy -4.662678 -4.62534)
			)
			(stroke
				(width 0)
				(type default)
			)
			(fill yes)
			(layer "F.SilkS")
		)
		(fp_line
			(start 3.750056 5.500116)
			(end 3.750056 -5.500116)
			(stroke
				(width 0.1)
				(type default)
			)
			(layer "F.Fab")
		)
		(fp_line
			(start 3.750056 -5.500116)
			(end -3.750056 -5.500116)
			(stroke
				(width 0.1)
				(type default)
			)
			(layer "F.Fab")
		)
		(fp_line
			(start -3.750056 5.500116)
			(end 3.750056 5.500116)
			(stroke
				(width 0.1)
				(type default)
			)
			(layer "F.Fab")
		)
		(fp_line
			(start -3.750056 -5.500116)
			(end -3.750056 5.500116)
			(stroke
				(width 0.1)
				(type default)
			)
			(layer "F.Fab")
		)
		(fp_poly
			(pts
				(xy -4.9276 -4.757928) (xy -4.9276 -3.741928) (xy -3.9116 -4.249928)
			)
			(stroke
				(width 0)
				(type default)
			)
			(fill yes)
			(layer "F.Fab")
		)
		(pad "1" smd rect
			(at 0 -4.249928 90)
			(size 2.413 4.5212)
			(layers "F.Cu" "F.Mask" "F.Paste")
			(net "SW_PVDDCR_CPU0_P0_SW4")
		)
		(pad "2" smd rect
			(at 0 -1.175004 90)
			(size 1.3716 4.5212)
			(layers "F.Cu" "F.Mask" "F.Paste")
			(net "IND_CPU0_P0_CPL3")
		)
		(pad "3" smd rect
			(at 0 1.175004 90)
			(size 1.3716 4.5212)
			(layers "F.Cu" "F.Mask" "F.Paste")
			(net "GND")
		)
		(pad "4" smd rect
			(at 0 4.249928 90)
			(size 2.413 4.5212)
			(layers "F.Cu" "F.Mask" "F.Paste")
			(net "PVDDCR_CPU0_P0")
		)
	)
	(footprint ""
		(layer "F.Cu")
		(at 50.711354 -373.03583 -90)
		(property "Reference" "C826"
			(at 0 0 270)
			(layer "F.SilkS")
			(hide yes)
			(effects
				(font
					(size 1.27 1.27)
				)
			)
		)
		(property "Value" ""
			(at 0 0 270)
			(layer "F.Fab")
			(effects
				(font
					(size 1.27 1.27)
				)
			)
		)
		(duplicate_pad_numbers_are_jumpers no)
		(fp_line
			(start -0.299974 0.150114)
			(end -0.299974 -0.150114)
			(stroke
				(width 0.1)
				(type default)
			)
			(layer "F.Fab")
		)
		(fp_line
			(start 0.299974 0.150114)
			(end -0.299974 0.150114)
			(stroke
				(width 0.1)
				(type default)
			)
			(layer "F.Fab")
		)
		(fp_line
			(start -0.299974 -0.150114)
			(end 0.299974 -0.150114)
			(stroke
				(width 0.1)
				(type default)
			)
			(layer "F.Fab")
		)
		(fp_line
			(start 0.299974 -0.150114)
			(end 0.299974 0.150114)
			(stroke
				(width 0.1)
				(type default)
			)
			(layer "F.Fab")
		)
		(pad "1" smd rect
			(at -0.2667 0 270)
			(size 0.3048 0.381)
			(layers "F.Cu" "F.Mask" "F.Paste")
			(net "P5E_CPU1_P0_TX_C_DN<5>")
		)
		(pad "2" smd rect
			(at 0.2667 0 270)
			(size 0.3048 0.381)
			(layers "F.Cu" "F.Mask" "F.Paste")
			(net "P5E_CPU1_P0_TX_DN<5>")
		)
	)
	(footprint ""
		(layer "F.Cu")
		(at 103.125524 -414.329626)
		(property "Reference" "R6863"
			(at 0 0 0)
			(layer "F.SilkS")
			(hide yes)
			(effects
				(font
					(size 1.27 1.27)
				)
			)
		)
		(property "Value" ""
			(at 0 0 0)
			(layer "F.Fab")
			(effects
				(font
					(size 1.27 1.27)
				)
			)
		)
		(duplicate_pad_numbers_are_jumpers no)
		(fp_line
			(start -0.7874 -0.4064)
			(end 0.7874 -0.4064)
			(stroke
				(width 0.1524)
				(type default)
			)
			(layer "F.SilkS")
		)
		(fp_line
			(start -0.7874 0.4064)
			(end -0.7874 -0.4064)
			(stroke
				(width 0.1524)
				(type default)
			)
			(layer "F.SilkS")
		)
		(fp_line
			(start 0.7874 -0.4064)
			(end 0.7874 0.4064)
			(stroke
				(width 0.1524)
				(type default)
			)
			(layer "F.SilkS")
		)
		(fp_line
			(start 0.7874 0.4064)
			(end -0.7874 0.4064)
			(stroke
				(width 0.1524)
				(type default)
			)
			(layer "F.SilkS")
		)
		(fp_line
			(start -0.67945 -0.305054)
			(end -0.12065 -0.305054)
			(stroke
				(width 0.1)
				(type default)
			)
			(layer "F.Fab")
		)
		(fp_line
			(start -0.67945 0.3048)
			(end -0.67945 -0.305054)
			(stroke
				(width 0.1)
				(type default)
			)
			(layer "F.Fab")
		)
		(fp_line
			(start -0.12065 -0.305054)
			(end -0.12065 -0.2794)
			(stroke
				(width 0.1)
				(type default)
			)
			(layer "F.Fab")
		)
		(fp_line
			(start -0.12065 -0.2794)
			(end 0.12065 -0.2794)
			(stroke
				(width 0.1)
				(type default)
			)
			(layer "F.Fab")
		)
		(fp_line
			(start -0.12065 0.2794)
			(end -0.12065 0.3048)
			(stroke
				(width 0.1)
				(type default)
			)
			(layer "F.Fab")
		)
		(fp_line
			(start -0.12065 0.3048)
			(end -0.67945 0.3048)
			(stroke
				(width 0.1)
				(type default)
			)
			(layer "F.Fab")
		)
		(fp_line
			(start 0.120396 0.2794)
			(end -0.12065 0.2794)
			(stroke
				(width 0.1)
				(type default)
			)
			(layer "F.Fab")
		)
		(fp_line
			(start 0.120396 0.3048)
			(end 0.120396 0.2794)
			(stroke
				(width 0.1)
				(type default)
			)
			(layer "F.Fab")
		)
		(fp_line
			(start 0.12065 -0.3048)
			(end 0.67945 -0.3048)
			(stroke
				(width 0.1)
				(type default)
			)
			(layer "F.Fab")
		)
		(fp_line
			(start 0.12065 -0.2794)
			(end 0.12065 -0.3048)
			(stroke
				(width 0.1)
				(type default)
			)
			(layer "F.Fab")
		)
		(fp_line
			(start 0.67945 -0.3048)
			(end 0.67945 0.3048)
			(stroke
				(width 0.1)
				(type default)
			)
			(layer "F.Fab")
		)
		(fp_line
			(start 0.67945 0.3048)
			(end 0.120396 0.3048)
			(stroke
				(width 0.1)
				(type default)
			)
			(layer "F.Fab")
		)
		(pad "1" smd circle
			(at -0.40005 0)
			(size 0 0)
			(layers "F.Cu" "F.Mask" "F.Paste")
			(net "SMB_HOST_CLK_3V3AUX_SDA_R1")
		)
		(pad "2" smd circle
			(at 0.40005 0)
			(size 0 0)
			(layers "F.Cu" "F.Mask" "F.Paste")
			(net "SMB_9ZXL045_P1_SDA")
		)
	)
	(footprint ""
		(layer "F.Cu")
		(at 412.472886 -75.880468 180)
		(property "Reference" "R3500"
			(at 0 0 180)
			(layer "F.SilkS")
			(hide yes)
			(effects
				(font
					(size 1.27 1.27)
				)
			)
		)
		(property "Value" ""
			(at 0 0 180)
			(layer "F.Fab")
			(effects
				(font
					(size 1.27 1.27)
				)
			)
		)
		(duplicate_pad_numbers_are_jumpers no)
		(fp_line
			(start 0.7874 0.4064)
			(end -0.7874 0.4064)
			(stroke
				(width 0.1524)
				(type default)
			)
			(layer "F.SilkS")
		)
		(fp_line
			(start 0.7874 -0.4064)
			(end 0.7874 0.4064)
			(stroke
				(width 0.1524)
				(type default)
			)
			(layer "F.SilkS")
		)
		(fp_line
			(start -0.7874 0.4064)
			(end -0.7874 -0.4064)
			(stroke
				(width 0.1524)
				(type default)
			)
			(layer "F.SilkS")
		)
		(fp_line
			(start -0.7874 -0.4064)
			(end 0.7874 -0.4064)
			(stroke
				(width 0.1524)
				(type default)
			)
			(layer "F.SilkS")
		)
		(fp_line
			(start 0.67945 0.3048)
			(end 0.120396 0.3048)
			(stroke
				(width 0.1)
				(type default)
			)
			(layer "F.Fab")
		)
		(fp_line
			(start 0.67945 -0.3048)
			(end 0.67945 0.3048)
			(stroke
				(width 0.1)
				(type default)
			)
			(layer "F.Fab")
		)
		(fp_line
			(start 0.12065 -0.2794)
			(end 0.12065 -0.3048)
			(stroke
				(width 0.1)
				(type default)
			)
			(layer "F.Fab")
		)
		(fp_line
			(start 0.12065 -0.3048)
			(end 0.67945 -0.3048)
			(stroke
				(width 0.1)
				(type default)
			)
			(layer "F.Fab")
		)
		(fp_line
			(start 0.120396 0.3048)
			(end 0.120396 0.2794)
			(stroke
				(width 0.1)
				(type default)
			)
			(layer "F.Fab")
		)
		(fp_line
			(start 0.120396 0.2794)
			(end -0.12065 0.2794)
			(stroke
				(width 0.1)
				(type default)
			)
			(layer "F.Fab")
		)
		(fp_line
			(start -0.12065 0.3048)
			(end -0.67945 0.3048)
			(stroke
				(width 0.1)
				(type default)
			)
			(layer "F.Fab")
		)
		(fp_line
			(start -0.12065 0.2794)
			(end -0.12065 0.3048)
			(stroke
				(width 0.1)
				(type default)
			)
			(layer "F.Fab")
		)
		(fp_line
			(start -0.12065 -0.2794)
			(end 0.12065 -0.2794)
			(stroke
				(width 0.1)
				(type default)
			)
			(layer "F.Fab")
		)
		(fp_line
			(start -0.12065 -0.305054)
			(end -0.12065 -0.2794)
			(stroke
				(width 0.1)
				(type default)
			)
			(layer "F.Fab")
		)
		(fp_line
			(start -0.67945 0.3048)
			(end -0.67945 -0.305054)
			(stroke
				(width 0.1)
				(type default)
			)
			(layer "F.Fab")
		)
		(fp_line
			(start -0.67945 -0.305054)
			(end -0.12065 -0.305054)
			(stroke
				(width 0.1)
				(type default)
			)
			(layer "F.Fab")
		)
		(pad "1" smd circle
			(at -0.40005 0 180)
			(size 0 0)
			(layers "F.Cu" "F.Mask" "F.Paste")
			(net "P3V3_OCP_SFF")
		)
		(pad "2" smd circle
			(at 0.40005 0 180)
			(size 0 0)
			(layers "F.Cu" "F.Mask" "F.Paste")
			(net "SMB_OCP_SFF_3V3AUX_BUF_SCL")
		)
	)
)
